(kicad_pcb
	(version 20241229)
	(generator "pcbnew")
	(generator_version "9.0")
	(general
		(thickness 1.6296)
		(legacy_teardrops no)
	)
	(paper "A3")
	(title_block
		(title "Thunderbolt to 10GbE adapter")
		(date "2026-04-21")
		(rev "1.1.0")
		(company "Antmicro Ltd")
		(comment 1 "www.antmicro.com")
		(comment 9 "footprints 541-545 of 703")
	)
	(layers
		(0 "F.Cu" signal)
		(4 "In1.Cu" signal)
		(6 "In2.Cu" signal)
		(8 "In3.Cu" signal)
		(10 "In4.Cu" signal)
		(12 "In5.Cu" signal)
		(14 "In6.Cu" signal)
		(2 "B.Cu" signal)
		(9 "F.Adhes" user "F.Adhesive")
		(11 "B.Adhes" user "B.Adhesive")
		(13 "F.Paste" user)
		(15 "B.Paste" user)
		(5 "F.SilkS" user "F.Silkscreen")
		(7 "B.SilkS" user "B.Silkscreen")
		(1 "F.Mask" user)
		(3 "B.Mask" user)
		(17 "Dwgs.User" user "User.Drawings")
		(19 "Cmts.User" user "User.Comments")
		(21 "Eco1.User" user "User.Eco1")
		(23 "Eco2.User" user "User.Eco2")
		(25 "Edge.Cuts" user)
		(27 "Margin" user)
		(31 "F.CrtYd" user "F.Courtyard")
		(29 "B.CrtYd" user "B.Courtyard")
		(35 "F.Fab" user)
		(33 "B.Fab" user)
	)
	(footprint "antmicro-footprints:C_0402_1005Metric"
		(layer "B.Cu")
		(at 130.449999 127.85 90)
		(descr "Capacitor SMD 0402")
		(tags "capacitor SMD 0402")
		(property "Reference" "C75"
			(at 7.700002 21.900002 270)
			(layer "B.SilkS")
			(effects
				(font
					(size 0.7 0.7)
					(thickness 0.15)
				)
				(justify mirror)
			)
		)
		(property "Value" "C_1u_0402"
			(at -1.022927 -2.155213 270)
			(layer "B.Fab")
			(effects
				(font
					(size 0.7 0.7)
					(thickness 0.15)
				)
				(justify left bottom mirror)
			)
		)
		(property "Datasheet" "https://product.tdk.com/en/search/capacitor/ceramic/mlcc/info?part_no=C1005X6S1A105K050BC"
			(at 0 0 270)
			(layer "B.Fab")
			(hide yes)
			(effects
				(font
					(size 1.27 1.27)
					(thickness 0.15)
				)
				(justify mirror)
			)
		)
		(property "Description" "SMD Multilayer Ceramic Capacitor, 1 µF, 10 V, 0402 [1005 Metric], ± 10%, X6S, C"
			(at 0 0 270)
			(layer "B.Fab")
			(hide yes)
			(effects
				(font
					(size 1.27 1.27)
					(thickness 0.15)
				)
				(justify mirror)
			)
		)
		(property "MPN" "C1005X6S1A105K050BC"
			(at 0 0 90)
			(unlocked yes)
			(layer "B.Fab")
			(hide yes)
			(effects
				(font
					(size 1 1)
					(thickness 0.15)
				)
				(justify mirror)
			)
		)
		(property "Manufacturer" "TDK"
			(at 0 0 90)
			(unlocked yes)
			(layer "B.Fab")
			(hide yes)
			(effects
				(font
					(size 1 1)
					(thickness 0.15)
				)
				(justify mirror)
			)
		)
		(property "License" "Apache-2.0"
			(at 0 0 90)
			(unlocked yes)
			(layer "B.Fab")
			(hide yes)
			(effects
				(font
					(size 1 1)
					(thickness 0.15)
				)
				(justify mirror)
			)
		)
		(property "Val" "1u"
			(at 0 0 90)
			(unlocked yes)
			(layer "B.Fab")
			(hide yes)
			(effects
				(font
					(size 1 1)
					(thickness 0.15)
				)
				(justify mirror)
			)
		)
		(property "Voltage" ""
			(at 0 0 90)
			(unlocked yes)
			(layer "B.Fab")
			(hide yes)
			(effects
				(font
					(size 1 1)
					(thickness 0.15)
				)
				(justify mirror)
			)
		)
		(property "Dielectric" ""
			(at 0 0 90)
			(unlocked yes)
			(layer "B.Fab")
			(hide yes)
			(effects
				(font
					(size 1 1)
					(thickness 0.15)
				)
				(justify mirror)
			)
		)
		(property "Author" "Antmicro"
			(at 0 0 90)
			(unlocked yes)
			(layer "B.Fab")
			(hide yes)
			(effects
				(font
					(size 1 1)
					(thickness 0.15)
				)
				(justify mirror)
			)
		)
		(sheetname "/TB Controller - Power/")
		(sheetfile "tb-power.kicad_sch")
		(attr smd)
		(fp_rect
			(start -0.925 0.47)
			(end 0.925 -0.47)
			(stroke
				(width 0.05)
				(type default)
			)
			(fill no)
			(layer "B.CrtYd")
		)
		(fp_line
			(start 0.504 -0.248)
			(end -0.494 -0.248)
			(stroke
				(width 0.15)
				(type solid)
			)
			(layer "B.Fab")
		)
		(fp_line
			(start -0.494 -0.248)
			(end -0.494 0.25)
			(stroke
				(width 0.15)
				(type solid)
			)
			(layer "B.Fab")
		)
		(fp_line
			(start 0.504 0.25)
			(end 0.504 -0.248)
			(stroke
				(width 0.15)
				(type solid)
			)
			(layer "B.Fab")
		)
		(fp_line
			(start -0.494 0.25)
			(end 0.504 0.25)
			(stroke
				(width 0.15)
				(type solid)
			)
			(layer "B.Fab")
		)
		(fp_text user "Author: Antmicro"
			(at -0.939 -3.399 270)
			(layer "B.Fab")
			(effects
				(font
					(size 0.7 0.7)
					(thickness 0.15)
				)
				(justify left bottom mirror)
			)
		)
		(fp_text user "${REFERENCE}"
			(at -0.939 -4.599 270)
			(layer "B.Fab")
			(effects
				(font
					(size 0.7 0.7)
					(thickness 0.15)
				)
				(justify left bottom mirror)
			)
		)
		(fp_text user "License: Apache-2.0"
			(at -0.939 -5.799 270)
			(layer "B.Fab")
			(effects
				(font
					(size 0.7 0.7)
					(thickness 0.15)
				)
				(justify left bottom mirror)
			)
		)
		(pad "1" smd roundrect
			(at -0.48 0 90)
			(size 0.59 0.64)
			(layers "B.Cu" "B.Mask" "B.Paste")
			(roundrect_rratio 0.25)
			(net 23 "GND")
			(pintype "passive")
		)
		(pad "2" smd roundrect
			(at 0.48 0 90)
			(size 0.59 0.64)
			(layers "B.Cu" "B.Mask" "B.Paste")
			(roundrect_rratio 0.25)
			(net 57 "+3V3_TB")
			(pintype "passive")
		)
	)
	(footprint "antmicro-footprints:R_0402_1005Metric"
		(layer "B.Cu")
		(at 125.222 119.951 -90)
		(descr "Resistor SMD 0402")
		(tags "resistor SMD 0402")
		(property "Reference" "R40"
			(at -7.700002 -21.900002 90)
			(layer "B.SilkS")
			(effects
				(font
					(size 0.7 0.7)
					(thickness 0.15)
				)
				(justify mirror)
			)
		)
		(property "Value" "R_14k_0402"
			(at -1.011843 -1.772047 90)
			(layer "B.Fab")
			(effects
				(font
					(size 0.7 0.7)
					(thickness 0.15)
				)
				(justify left bottom mirror)
			)
		)
		(property "Datasheet" "https://www.bourns.com/docs/product-datasheets/cr.pdf"
			(at 0 0 90)
			(layer "B.Fab")
			(hide yes)
			(effects
				(font
					(size 1.27 1.27)
					(thickness 0.15)
				)
				(justify mirror)
			)
		)
		(property "Description" "SMD Chip Resistor, 14 kohm, ± 1%, 100 mW, 0402 [1005 Metric], Thick Film, Precision"
			(at 0 0 90)
			(layer "B.Fab")
			(hide yes)
			(effects
				(font
					(size 1.27 1.27)
					(thickness 0.15)
				)
				(justify mirror)
			)
		)
		(property "MPN" "CR0402-FX-1402GLF"
			(at 0 0 270)
			(unlocked yes)
			(layer "B.Fab")
			(hide yes)
			(effects
				(font
					(size 1 1)
					(thickness 0.15)
				)
				(justify mirror)
			)
		)
		(property "Manufacturer" "Bourns"
			(at 0 0 270)
			(unlocked yes)
			(layer "B.Fab")
			(hide yes)
			(effects
				(font
					(size 1 1)
					(thickness 0.15)
				)
				(justify mirror)
			)
		)
		(property "License" "Apache-2.0"
			(at 0 0 270)
			(unlocked yes)
			(layer "B.Fab")
			(hide yes)
			(effects
				(font
					(size 1 1)
					(thickness 0.15)
				)
				(justify mirror)
			)
		)
		(property "Val" "14k"
			(at 0 0 270)
			(unlocked yes)
			(layer "B.Fab")
			(hide yes)
			(effects
				(font
					(size 1 1)
					(thickness 0.15)
				)
				(justify mirror)
			)
		)
		(property "Tolerance" "1%"
			(at 0 0 270)
			(unlocked yes)
			(layer "B.Fab")
			(hide yes)
			(effects
				(font
					(size 1 1)
					(thickness 0.15)
				)
				(justify mirror)
			)
		)
		(property "Author" "Antmicro"
			(at 0 0 270)
			(unlocked yes)
			(layer "B.Fab")
			(hide yes)
			(effects
				(font
					(size 1 1)
					(thickness 0.15)
				)
				(justify mirror)
			)
		)
		(sheetname "/TB Controller/")
		(sheetfile "tb.kicad_sch")
		(attr smd dnp)
		(fp_rect
			(start -0.925 0.47)
			(end 0.925 -0.47)
			(stroke
				(width 0.05)
				(type default)
			)
			(fill no)
			(layer "B.CrtYd")
		)
		(fp_rect
			(start -0.5 0.25)
			(end 0.5 -0.25)
			(stroke
				(width 0.15)
				(type solid)
			)
			(fill no)
			(layer "B.Fab")
		)
		(fp_text user "${REFERENCE}"
			(at -0.95 -3.168 90)
			(layer "B.Fab")
			(effects
				(font
					(size 0.7 0.7)
					(thickness 0.15)
				)
				(justify left bottom mirror)
			)
		)
		(fp_text user "License: Apache-2.0"
			(at -0.95 -5.169 90)
			(layer "B.Fab")
			(effects
				(font
					(size 0.7 0.7)
					(thickness 0.15)
				)
				(justify left bottom mirror)
			)
		)
		(fp_text user "Author: Antmicro"
			(at -0.95 -4.169 90)
			(layer "B.Fab")
			(effects
				(font
					(size 0.7 0.7)
					(thickness 0.15)
				)
				(justify left bottom mirror)
			)
		)
		(pad "1" smd roundrect
			(at -0.48 0 270)
			(size 0.59 0.64)
			(layers "B.Cu" "B.Mask" "B.Paste")
			(roundrect_rratio 0.25)
			(net 23 "GND")
			(pintype "passive")
		)
		(pad "2" smd roundrect
			(at 0.48 0 270)
			(size 0.59 0.64)
			(layers "B.Cu" "B.Mask" "B.Paste")
			(roundrect_rratio 0.25)
			(net 223 "Net-(U4C-DPSNK_RBIAS)")
			(pintype "passive")
		)
	)
	(footprint "antmicro-footprints:R_0402_1005Metric"
		(layer "B.Cu")
		(at 154.481866 76.760116 90)
		(descr "Resistor SMD 0402")
		(tags "resistor SMD 0402")
		(property "Reference" "R153"
			(at -8.839884 21.618136 270)
			(layer "B.SilkS")
			(effects
				(font
					(size 0.7 0.7)
					(thickness 0.15)
				)
				(justify mirror)
			)
		)
		(property "Value" "R_1k_0402"
			(at -1.011843 -1.772047 270)
			(layer "B.Fab")
			(effects
				(font
					(size 0.7 0.7)
					(thickness 0.15)
				)
				(justify left bottom mirror)
			)
		)
		(property "Datasheet" "https://www.bourns.com/docs/product-datasheets/cr.pdf"
			(at 0 0 270)
			(layer "B.Fab")
			(hide yes)
			(effects
				(font
					(size 1.27 1.27)
					(thickness 0.15)
				)
				(justify mirror)
			)
		)
		(property "Description" "SMD Chip Resistor, 1 kohm, ± 1%, 63 mW, 0402 [1005 Metric], Thick Film, General Purpose"
			(at 0 0 270)
			(layer "B.Fab")
			(hide yes)
			(effects
				(font
					(size 1.27 1.27)
					(thickness 0.15)
				)
				(justify mirror)
			)
		)
		(property "MPN" "CR0402-FX-1001GLF"
			(at 0 0 90)
			(unlocked yes)
			(layer "B.Fab")
			(hide yes)
			(effects
				(font
					(size 1 1)
					(thickness 0.15)
				)
				(justify mirror)
			)
		)
		(property "Manufacturer" "Bourns"
			(at 0 0 90)
			(unlocked yes)
			(layer "B.Fab")
			(hide yes)
			(effects
				(font
					(size 1 1)
					(thickness 0.15)
				)
				(justify mirror)
			)
		)
		(property "License" "Apache-2.0"
			(at 0 0 90)
			(unlocked yes)
			(layer "B.Fab")
			(hide yes)
			(effects
				(font
					(size 1 1)
					(thickness 0.15)
				)
				(justify mirror)
			)
		)
		(property "Author" "Antmicro"
			(at 0 0 90)
			(unlocked yes)
			(layer "B.Fab")
			(hide yes)
			(effects
				(font
					(size 1 1)
					(thickness 0.15)
				)
				(justify mirror)
			)
		)
		(property "Val" "1k"
			(at 0 0 90)
			(unlocked yes)
			(layer "B.Fab")
			(hide yes)
			(effects
				(font
					(size 1 1)
					(thickness 0.15)
				)
				(justify mirror)
			)
		)
		(property "Tolerance" "1%"
			(at 0 0 90)
			(unlocked yes)
			(layer "B.Fab")
			(hide yes)
			(effects
				(font
					(size 1 1)
					(thickness 0.15)
				)
				(justify mirror)
			)
		)
		(sheetname "/X710-AT2 Misc/")
		(sheetfile "x710-at2-mics.kicad_sch")
		(attr smd)
		(fp_rect
			(start -0.925 0.47)
			(end 0.925 -0.47)
			(stroke
				(width 0.05)
				(type default)
			)
			(fill no)
			(layer "B.CrtYd")
		)
		(fp_rect
			(start -0.5 0.25)
			(end 0.5 -0.25)
			(stroke
				(width 0.15)
				(type solid)
			)
			(fill no)
			(layer "B.Fab")
		)
		(fp_text user "Author: Antmicro"
			(at -0.95 -4.169 270)
			(layer "B.Fab")
			(effects
				(font
					(size 0.7 0.7)
					(thickness 0.15)
				)
				(justify left bottom mirror)
			)
		)
		(fp_text user "${REFERENCE}"
			(at -0.95 -3.168 270)
			(layer "B.Fab")
			(effects
				(font
					(size 0.7 0.7)
					(thickness 0.15)
				)
				(justify left bottom mirror)
			)
		)
		(fp_text user "License: Apache-2.0"
			(at -0.95 -5.169 270)
			(layer "B.Fab")
			(effects
				(font
					(size 0.7 0.7)
					(thickness 0.15)
				)
				(justify left bottom mirror)
			)
		)
		(pad "1" smd roundrect
			(at -0.48 0 90)
			(size 0.59 0.64)
			(layers "B.Cu" "B.Mask" "B.Paste")
			(roundrect_rratio 0.25)
			(net 23 "GND")
			(pintype "passive")
		)
		(pad "2" smd roundrect
			(at 0.48 0 90)
			(size 0.59 0.64)
			(layers "B.Cu" "B.Mask" "B.Paste")
			(roundrect_rratio 0.25)
			(net 87 "/X710-AT2 Misc/RSVD_J11_VSS")
			(pintype "passive")
		)
	)
	(footprint "antmicro-footprints:C_0402_1005Metric"
		(layer "B.Cu")
		(at 138.35 137.599999 180)
		(descr "Capacitor SMD 0402")
		(tags "capacitor SMD 0402")
		(property "Reference" "C12"
			(at -19.525001 8.1 0)
			(layer "B.SilkS")
			(effects
				(font
					(size 0.7 0.7)
					(thickness 0.15)
				)
				(justify mirror)
			)
		)
		(property "Value" "C_4u7_25V_0402"
			(at -1.022927 -2.155213 0)
			(layer "B.Fab")
			(effects
				(font
					(size 0.7 0.7)
					(thickness 0.15)
				)
				(justify left bottom mirror)
			)
		)
		(property "Datasheet" "https://www.murata.com/products/productdetail?partno=GRM155C61E475ME15%23"
			(at 0 0 0)
			(layer "B.Fab")
			(hide yes)
			(effects
				(font
					(size 1.27 1.27)
					(thickness 0.15)
				)
				(justify mirror)
			)
		)
		(property "Description" "SMD Multilayer Ceramic Capacitor"
			(at 0 0 0)
			(layer "B.Fab")
			(hide yes)
			(effects
				(font
					(size 1.27 1.27)
					(thickness 0.15)
				)
				(justify mirror)
			)
		)
		(property "MPN" "GRM155C61E475ME15J"
			(at 0 0 180)
			(unlocked yes)
			(layer "B.Fab")
			(hide yes)
			(effects
				(font
					(size 1 1)
					(thickness 0.15)
				)
				(justify mirror)
			)
		)
		(property "Manufacturer" "Murata"
			(at 0 0 180)
			(unlocked yes)
			(layer "B.Fab")
			(hide yes)
			(effects
				(font
					(size 1 1)
					(thickness 0.15)
				)
				(justify mirror)
			)
		)
		(property "License" "Apache-2.0"
			(at 0 0 180)
			(unlocked yes)
			(layer "B.Fab")
			(hide yes)
			(effects
				(font
					(size 1 1)
					(thickness 0.15)
				)
				(justify mirror)
			)
		)
		(property "Val" "4u7"
			(at 0 0 180)
			(unlocked yes)
			(layer "B.Fab")
			(hide yes)
			(effects
				(font
					(size 1 1)
					(thickness 0.15)
				)
				(justify mirror)
			)
		)
		(property "Voltage" "25V"
			(at 0 0 180)
			(unlocked yes)
			(layer "B.Fab")
			(hide yes)
			(effects
				(font
					(size 1 1)
					(thickness 0.15)
				)
				(justify mirror)
			)
		)
		(property "Dielectric" "X5S"
			(at 0 0 180)
			(unlocked yes)
			(layer "B.Fab")
			(hide yes)
			(effects
				(font
					(size 1 1)
					(thickness 0.15)
				)
				(justify mirror)
			)
		)
		(property "Author" "Antmicro"
			(at 0 0 180)
			(unlocked yes)
			(layer "B.Fab")
			(hide yes)
			(effects
				(font
					(size 1 1)
					(thickness 0.15)
				)
				(justify mirror)
			)
		)
		(sheetname "/PD and TB DC-DC/")
		(sheetfile "PD_and_TB_DC_DC.kicad_sch")
		(attr smd)
		(fp_rect
			(start -0.925 0.47)
			(end 0.925 -0.47)
			(stroke
				(width 0.05)
				(type default)
			)
			(fill no)
			(layer "B.CrtYd")
		)
		(fp_line
			(start 0.504 0.25)
			(end 0.504 -0.248)
			(stroke
				(width 0.15)
				(type solid)
			)
			(layer "B.Fab")
		)
		(fp_line
			(start 0.504 -0.248)
			(end -0.494 -0.248)
			(stroke
				(width 0.15)
				(type solid)
			)
			(layer "B.Fab")
		)
		(fp_line
			(start -0.494 0.25)
			(end 0.504 0.25)
			(stroke
				(width 0.15)
				(type solid)
			)
			(layer "B.Fab")
		)
		(fp_line
			(start -0.494 -0.248)
			(end -0.494 0.25)
			(stroke
				(width 0.15)
				(type solid)
			)
			(layer "B.Fab")
		)
		(fp_text user "Author: Antmicro"
			(at -0.939 -3.399 0)
			(layer "B.Fab")
			(effects
				(font
					(size 0.7 0.7)
					(thickness 0.15)
				)
				(justify left bottom mirror)
			)
		)
		(fp_text user "${REFERENCE}"
			(at -0.939 -4.599 0)
			(layer "B.Fab")
			(effects
				(font
					(size 0.7 0.7)
					(thickness 0.15)
				)
				(justify left bottom mirror)
			)
		)
		(fp_text user "License: Apache-2.0"
			(at -0.939 -5.799 0)
			(layer "B.Fab")
			(effects
				(font
					(size 0.7 0.7)
					(thickness 0.15)
				)
				(justify left bottom mirror)
			)
		)
		(pad "1" smd roundrect
			(at -0.48 0 180)
			(size 0.59 0.64)
			(layers "B.Cu" "B.Mask" "B.Paste")
			(roundrect_rratio 0.25)
			(net 23 "GND")
			(pintype "passive")
		)
		(pad "2" smd roundrect
			(at 0.48 0 180)
			(size 0.59 0.64)
			(layers "B.Cu" "B.Mask" "B.Paste")
			(roundrect_rratio 0.25)
			(net 170 "PP_HV")
			(pintype "passive")
		)
	)
	(footprint "antmicro-footprints:R_0402_1005Metric"
		(layer "B.Cu")
		(at 140.6 117.149997)
		(descr "Resistor SMD 0402")
		(tags "resistor SMD 0402")
		(property "Reference" "R62"
			(at 19.525001 -7.450001 180)
			(layer "B.SilkS")
			(effects
				(font
					(size 0.7 0.7)
					(thickness 0.15)
				)
				(justify mirror)
			)
		)
		(property "Value" "R_10k_0402"
			(at -1.011843 -1.772047 180)
			(layer "B.Fab")
			(effects
				(font
					(size 0.7 0.7)
					(thickness 0.15)
				)
				(justify left bottom mirror)
			)
		)
		(property "Datasheet" "https://www.bourns.com/docs/product-datasheets/cr.pdf"
			(at 0 0 180)
			(layer "B.Fab")
			(hide yes)
			(effects
				(font
					(size 1.27 1.27)
					(thickness 0.15)
				)
				(justify mirror)
			)
		)
		(property "Description" "SMD Chip Resistor, 10 kohm, ± 1%, 62.5 mW, 0402 [1005 Metric], Thick Film, General Purpose"
			(at 0 0 180)
			(layer "B.Fab")
			(hide yes)
			(effects
				(font
					(size 1.27 1.27)
					(thickness 0.15)
				)
				(justify mirror)
			)
		)
		(property "MPN" "CR0402-FX-1002GLF"
			(at 0 0 0)
			(unlocked yes)
			(layer "B.Fab")
			(hide yes)
			(effects
				(font
					(size 1 1)
					(thickness 0.15)
				)
				(justify mirror)
			)
		)
		(property "Manufacturer" "Bourns"
			(at 0 0 0)
			(unlocked yes)
			(layer "B.Fab")
			(hide yes)
			(effects
				(font
					(size 1 1)
					(thickness 0.15)
				)
				(justify mirror)
			)
		)
		(property "License" "Apache-2.0"
			(at 0 0 0)
			(unlocked yes)
			(layer "B.Fab")
			(hide yes)
			(effects
				(font
					(size 1 1)
					(thickness 0.15)
				)
				(justify mirror)
			)
		)
		(property "Val" "10k"
			(at 0 0 0)
			(unlocked yes)
			(layer "B.Fab")
			(hide yes)
			(effects
				(font
					(size 1 1)
					(thickness 0.15)
				)
				(justify mirror)
			)
		)
		(property "Tolerance" "1%"
			(at 0 0 0)
			(unlocked yes)
			(layer "B.Fab")
			(hide yes)
			(effects
				(font
					(size 1 1)
					(thickness 0.15)
				)
				(justify mirror)
			)
		)
		(property "Author" "Antmicro"
			(at 0 0 0)
			(unlocked yes)
			(layer "B.Fab")
			(hide yes)
			(effects
				(font
					(size 1 1)
					(thickness 0.15)
				)
				(justify mirror)
			)
		)
		(sheetname "/TB Controller/")
		(sheetfile "tb.kicad_sch")
		(attr smd)
		(fp_rect
			(start -0.925 0.47)
			(end 0.925 -0.47)
			(stroke
				(width 0.05)
				(type default)
			)
			(fill no)
			(layer "B.CrtYd")
		)
		(fp_rect
			(start -0.5 0.25)
			(end 0.5 -0.25)
			(stroke
				(width 0.15)
				(type solid)
			)
			(fill no)
			(layer "B.Fab")
		)
		(fp_text user "${REFERENCE}"
			(at -0.95 -3.168 180)
			(layer "B.Fab")
			(effects
				(font
					(size 0.7 0.7)
					(thickness 0.15)
				)
				(justify left bottom mirror)
			)
		)
		(fp_text user "License: Apache-2.0"
			(at -0.95 -5.169 180)
			(layer "B.Fab")
			(effects
				(font
					(size 0.7 0.7)
					(thickness 0.15)
				)
				(justify left bottom mirror)
			)
		)
		(fp_text user "Author: Antmicro"
			(at -0.95 -4.169 180)
			(layer "B.Fab")
			(effects
				(font
					(size 0.7 0.7)
					(thickness 0.15)
				)
				(justify left bottom mirror)
			)
		)
		(pad "1" smd roundrect
			(at -0.48 0)
			(size 0.59 0.64)
			(layers "B.Cu" "B.Mask" "B.Paste")
			(roundrect_rratio 0.25)
			(net 57 "+3V3_TB")
			(pintype "passive")
		)
		(pad "2" smd roundrect
			(at 0.48 0)
			(size 0.59 0.64)
			(layers "B.Cu" "B.Mask" "B.Paste")
			(roundrect_rratio 0.25)
			(net 224 "Net-(U4D-TDI)")
			(pintype "passive")
		)
	)
)
